(kicad_pcb
	(version 20241229)
	(generator "pcbnew")
	(generator_version "9.0")
	(general
		(thickness 1.62)
		(legacy_teardrops no)
	)
	(paper "A4")
	(title_block
		(title "OCuLink to 10GbE adapter")
		(date "2026-02-23")
		(rev "1.1.0")
		(company "Antmicro Ltd")
		(comment 1 "www.antmicro.com")
		(comment 9 "footprints 214-219 of 510")
	)
	(layers
		(0 "F.Cu" signal)
		(4 "In1.Cu" signal)
		(6 "In2.Cu" signal)
		(8 "In3.Cu" signal)
		(10 "In4.Cu" signal)
		(12 "In5.Cu" signal)
		(14 "In6.Cu" signal)
		(2 "B.Cu" signal)
		(9 "F.Adhes" user "F.Adhesive")
		(11 "B.Adhes" user "B.Adhesive")
		(13 "F.Paste" user)
		(15 "B.Paste" user)
		(5 "F.SilkS" user "F.Silkscreen")
		(7 "B.SilkS" user "B.Silkscreen")
		(1 "F.Mask" user)
		(3 "B.Mask" user)
		(17 "Dwgs.User" user "User.Drawings")
		(19 "Cmts.User" user "User.Comments")
		(21 "Eco1.User" user "User.Eco1")
		(23 "Eco2.User" user "User.Eco2")
		(25 "Edge.Cuts" user)
		(27 "Margin" user)
		(31 "F.CrtYd" user "F.Courtyard")
		(29 "B.CrtYd" user "B.Courtyard")
		(35 "F.Fab" user)
		(33 "B.Fab" user)
	)
	(footprint "antmicro-footprints:C_0603_1608Metric_EIA"
		(layer "F.Cu")
		(at 60.649999 107.2)
		(descr "Capacitor SMD 0603, IPC-7351 Density Level A")
		(tags "Capacitor 0603")
		(property "Reference" "C34"
			(at -3.219999 -0.61 0)
			(layer "F.SilkS")
			(effects
				(font
					(size 0.7 0.7)
					(thickness 0.15)
				)
				(justify left bottom)
			)
		)
		(property "Value" "C_22u_16V_0603"
			(at -1.42757 1.770288 0)
			(layer "F.Fab")
			(hide yes)
			(effects
				(font
					(size 0.7 0.7)
					(thickness 0.15)
				)
				(justify left bottom)
			)
		)
		(property "Datasheet" "https://product.samsungsem.com/mlcc/CL10A226MO7JZN.do"
			(at 0 0 0)
			(layer "F.Fab")
			(hide yes)
			(effects
				(font
					(size 1.27 1.27)
					(thickness 0.15)
				)
			)
		)
		(property "Description" "SMD Multilayer Ceramic Capacitor"
			(at 0 0 0)
			(layer "F.Fab")
			(hide yes)
			(effects
				(font
					(size 1.27 1.27)
					(thickness 0.15)
				)
			)
		)
		(property "MPN" "CL10A226MO7JZNC"
			(at 0 0 0)
			(unlocked yes)
			(layer "F.Fab")
			(hide yes)
			(effects
				(font
					(size 1 1)
					(thickness 0.15)
				)
			)
		)
		(property "Manufacturer" "Samsung Electro-Mechanics"
			(at 0 0 0)
			(unlocked yes)
			(layer "F.Fab")
			(hide yes)
			(effects
				(font
					(size 1 1)
					(thickness 0.15)
				)
			)
		)
		(property "License" "Apache-2.0"
			(at 0 0 0)
			(unlocked yes)
			(layer "F.Fab")
			(hide yes)
			(effects
				(font
					(size 1 1)
					(thickness 0.15)
				)
			)
		)
		(property "Author" "Antmicro"
			(at 0 0 0)
			(unlocked yes)
			(layer "F.Fab")
			(hide yes)
			(effects
				(font
					(size 1 1)
					(thickness 0.15)
				)
			)
		)
		(property "Val" "22u"
			(at 0 0 0)
			(unlocked yes)
			(layer "F.Fab")
			(hide yes)
			(effects
				(font
					(size 1 1)
					(thickness 0.15)
				)
			)
		)
		(property "Voltage" "16V"
			(at 0 0 0)
			(unlocked yes)
			(layer "F.Fab")
			(hide yes)
			(effects
				(font
					(size 1 1)
					(thickness 0.15)
				)
			)
		)
		(property "Dielectric" ""
			(at 0 0 0)
			(unlocked yes)
			(layer "F.Fab")
			(hide yes)
			(effects
				(font
					(size 1 1)
					(thickness 0.15)
				)
			)
		)
		(property "Public" "False"
			(at 0 0 0)
			(unlocked yes)
			(layer "F.Fab")
			(hide yes)
			(effects
				(font
					(size 1 1)
					(thickness 0.15)
				)
			)
		)
		(sheetname "/Power/")
		(sheetfile "power.kicad_sch")
		(attr smd)
		(fp_line
			(start -0.15 -0.55)
			(end 0.15 -0.55)
			(stroke
				(width 0.15)
				(type solid)
			)
			(layer "F.SilkS")
		)
		(fp_line
			(start -0.15 0.55)
			(end 0.15 0.55)
			(stroke
				(width 0.15)
				(type solid)
			)
			(layer "F.SilkS")
		)
		(fp_rect
			(start -1.25 -0.65)
			(end 1.25 0.65)
			(stroke
				(width 0.05)
				(type solid)
			)
			(fill no)
			(layer "F.CrtYd")
		)
		(fp_rect
			(start -0.8 -0.45)
			(end 0.8 0.45)
			(stroke
				(width 0.15)
				(type solid)
			)
			(fill no)
			(layer "F.Fab")
		)
		(pad "1" smd roundrect
			(at -0.7 0)
			(size 0.8 1.1)
			(layers "F.Cu" "F.Mask" "F.Paste")
			(roundrect_rratio 0.2)
			(net 28 "GND")
			(pintype "passive")
		)
		(pad "2" smd roundrect
			(at 0.7 0)
			(size 0.8 1.1)
			(layers "F.Cu" "F.Mask" "F.Paste")
			(roundrect_rratio 0.2)
			(net 312 "/Power/+1V0_OUT")
			(pintype "passive")
		)
	)
	(footprint "antmicro-footprints:R_0402_1005Metric"
		(layer "F.Cu")
		(at 99.349999 107.099999 180)
		(descr "Resistor SMD 0402")
		(tags "resistor SMD 0402")
		(property "Reference" "R45"
			(at 1.249999 -15.550001 0)
			(layer "F.SilkS")
			(effects
				(font
					(size 0.7 0.7)
					(thickness 0.15)
				)
				(justify left bottom)
			)
		)
		(property "Value" "R_150R_0402"
			(at -1.011843 1.772046 0)
			(layer "F.Fab")
			(hide yes)
			(effects
				(font
					(size 0.7 0.7)
					(thickness 0.15)
				)
				(justify right top)
			)
		)
		(property "Datasheet" "https://www.bourns.com/docs/product-datasheets/cr.pdf"
			(at 0 0 0)
			(layer "F.Fab")
			(hide yes)
			(effects
				(font
					(size 1.27 1.27)
					(thickness 0.15)
				)
			)
		)
		(property "Description" "SMD Chip Resistor, 150 ohm, ± 1%, 62.5 mW, 0402 [1005 Metric], Thick Film, General Purpose"
			(at 0 0 0)
			(layer "F.Fab")
			(hide yes)
			(effects
				(font
					(size 1.27 1.27)
					(thickness 0.15)
				)
			)
		)
		(property "MPN" "CR0402-FX-1500GLF"
			(at 0 0 180)
			(unlocked yes)
			(layer "F.Fab")
			(hide yes)
			(effects
				(font
					(size 1 1)
					(thickness 0.15)
				)
			)
		)
		(property "Manufacturer" "Bourns"
			(at 0 0 180)
			(unlocked yes)
			(layer "F.Fab")
			(hide yes)
			(effects
				(font
					(size 1 1)
					(thickness 0.15)
				)
			)
		)
		(property "License" "Apache-2.0"
			(at 0 0 180)
			(unlocked yes)
			(layer "F.Fab")
			(hide yes)
			(effects
				(font
					(size 1 1)
					(thickness 0.15)
				)
			)
		)
		(property "Author" "Antmicro"
			(at 0 0 180)
			(unlocked yes)
			(layer "F.Fab")
			(hide yes)
			(effects
				(font
					(size 1 1)
					(thickness 0.15)
				)
			)
		)
		(property "Val" "150R"
			(at 0 0 180)
			(unlocked yes)
			(layer "F.Fab")
			(hide yes)
			(effects
				(font
					(size 1 1)
					(thickness 0.15)
				)
			)
		)
		(property "Tolerance" "1%"
			(at 0 0 180)
			(unlocked yes)
			(layer "F.Fab")
			(hide yes)
			(effects
				(font
					(size 1 1)
					(thickness 0.15)
				)
			)
		)
		(sheetname "/X710-AT2 10GbE/")
		(sheetfile "x710-at2-10gbe.kicad_sch")
		(attr smd)
		(fp_rect
			(start -0.925 -0.47)
			(end 0.925 0.47)
			(stroke
				(width 0.05)
				(type default)
			)
			(fill no)
			(layer "F.CrtYd")
		)
		(fp_rect
			(start -0.5 -0.25)
			(end 0.5 0.25)
			(stroke
				(width 0.15)
				(type solid)
			)
			(fill no)
			(layer "F.Fab")
		)
		(pad "1" smd roundrect
			(at -0.48 0 180)
			(size 0.59 0.64)
			(layers "F.Cu" "F.Mask" "F.Paste")
			(roundrect_rratio 0.25)
			(net 28 "GND")
			(pintype "passive")
		)
		(pad "2" smd roundrect
			(at 0.48 0 180)
			(size 0.59 0.64)
			(layers "F.Cu" "F.Mask" "F.Paste")
			(roundrect_rratio 0.25)
			(net 30 "/X710-AT2 10GbE/25MHZ_OSC_AC.+")
			(pintype "passive")
		)
	)
	(footprint "antmicro-footprints:MP_Pad6mm_Drill3.2mm"
		(layer "F.Cu")
		(at 106.975 77.995)
		(property "Reference" "MP6"
			(at 0 -3.2 0)
			(layer "F.SilkS")
			(hide yes)
			(effects
				(font
					(size 0.7 0.7)
					(thickness 0.15)
				)
				(justify left bottom)
			)
		)
		(property "Value" "MP_Pad6mm_Drill3.2mm"
			(at 0 3.9 0)
			(layer "F.Fab")
			(hide yes)
			(effects
				(font
					(size 0.7 0.7)
					(thickness 0.15)
				)
				(justify left bottom)
			)
		)
		(property "Description" "Mechanical part"
			(at 0 0 0)
			(layer "F.Fab")
			(hide yes)
			(effects
				(font
					(size 1.27 1.27)
					(thickness 0.15)
				)
			)
		)
		(property "Author" "Antmicro"
			(at 0 0 0)
			(unlocked yes)
			(layer "F.Fab")
			(hide yes)
			(effects
				(font
					(size 1 1)
					(thickness 0.15)
				)
			)
		)
		(property "License" "Apache-2.0"
			(at 0 0 0)
			(unlocked yes)
			(layer "F.Fab")
			(hide yes)
			(effects
				(font
					(size 1 1)
					(thickness 0.15)
				)
			)
		)
		(sheetname "/")
		(sheetfile "oculink-to-10gbe-adapter.kicad_sch")
		(attr exclude_from_pos_files exclude_from_bom)
		(fp_circle
			(center 0 0)
			(end 3.25 0)
			(stroke
				(width 0.05)
				(type default)
			)
			(fill no)
			(layer "F.CrtYd")
		)
		(fp_text user "License: Apache-2.0"
			(at -0.178 8.425 0)
			(layer "F.Fab")
			(effects
				(font
					(size 0.7 0.7)
					(thickness 0.15)
				)
				(justify left bottom)
			)
		)
		(fp_text user "${REFERENCE}"
			(at -0.178 6.025 0)
			(layer "F.Fab")
			(effects
				(font
					(size 0.7 0.7)
					(thickness 0.15)
				)
				(justify left bottom)
			)
		)
		(fp_text user "Author: Antmicro"
			(at -0.178 7.225 0)
			(layer "F.Fab")
			(effects
				(font
					(size 0.7 0.7)
					(thickness 0.15)
				)
				(justify left bottom)
			)
		)
		(pad "1" thru_hole circle
			(at 0 0)
			(size 6 6)
			(drill 3.2)
			(layers "*.Cu" "*.Mask")
			(remove_unused_layers no)
			(net 28 "GND")
			(pintype "passive")
		)
	)
	(footprint "antmicro-footprints:SOT-23-5"
		(layer "F.Cu")
		(at 115.9 103.4 180)
		(property "Reference" "U6"
			(at -2.05 -1.77 0)
			(layer "F.SilkS")
			(effects
				(font
					(size 0.7 0.7)
					(thickness 0.15)
				)
				(justify right top)
			)
		)
		(property "Value" "LP2985IM5X-5.0_SOT"
			(at 0.002 2.799 0)
			(layer "F.Fab")
			(hide yes)
			(effects
				(font
					(size 0.7 0.7)
					(thickness 0.15)
				)
				(justify right top)
			)
		)
		(property "Datasheet" "https://www.ti.com/lit/ds/symlink/lp2985-n.pdf?ts=1705246249323&ref_url=https%253A%252F%252Fwww.mouser.se%252F"
			(at 0 0 0)
			(layer "F.Fab")
			(hide yes)
			(effects
				(font
					(size 1.27 1.27)
					(thickness 0.15)
				)
			)
		)
		(property "Description" "LDO voltage regulator 150-mA, 16-V, low-dropout voltage regulator with enable 5-SOT-23"
			(at 0 0 0)
			(layer "F.Fab")
			(hide yes)
			(effects
				(font
					(size 1.27 1.27)
					(thickness 0.15)
				)
			)
		)
		(property "MPN" "LP2985IM5X-5.0/NOPB"
			(at 0 0 180)
			(unlocked yes)
			(layer "F.Fab")
			(hide yes)
			(effects
				(font
					(size 1 1)
					(thickness 0.15)
				)
			)
		)
		(property "Manufacturer" "Texas Instruments"
			(at 0 0 180)
			(unlocked yes)
			(layer "F.Fab")
			(hide yes)
			(effects
				(font
					(size 1 1)
					(thickness 0.15)
				)
			)
		)
		(property "Author" "Antmicro"
			(at 0 0 180)
			(unlocked yes)
			(layer "F.Fab")
			(hide yes)
			(effects
				(font
					(size 1 1)
					(thickness 0.15)
				)
			)
		)
		(property "License" "Apache-2.0"
			(at 0 0 180)
			(unlocked yes)
			(layer "F.Fab")
			(hide yes)
			(effects
				(font
					(size 1 1)
					(thickness 0.15)
				)
			)
		)
		(sheetname "/Fan controller/")
		(sheetfile "fan-controller.kicad_sch")
		(attr smd exclude_from_pos_files exclude_from_bom dnp)
		(fp_line
			(start 0.8 1.599)
			(end 0.549 1.599)
			(stroke
				(width 0.15)
				(type solid)
			)
			(layer "F.SilkS")
		)
		(fp_line
			(start 0.8 1.3)
			(end 0.8 1.599)
			(stroke
				(width 0.15)
				(type solid)
			)
			(layer "F.SilkS")
		)
		(fp_line
			(start 0.8 0.55)
			(end 0.8 -0.55)
			(stroke
				(width 0.15)
				(type solid)
			)
			(layer "F.SilkS")
		)
		(fp_line
			(start 0.8 -1.3)
			(end 0.8 -1.6)
			(stroke
				(width 0.15)
				(type solid)
			)
			(layer "F.SilkS")
		)
		(fp_line
			(start 0.8 -1.6)
			(end 0.5 -1.6)
			(stroke
				(width 0.15)
				(type solid)
			)
			(layer "F.SilkS")
		)
		(fp_line
			(start -0.55 1.6)
			(end -0.85 1.6)
			(stroke
				(width 0.15)
				(type solid)
			)
			(layer "F.SilkS")
		)
		(fp_line
			(start -0.8 -1.6)
			(end -0.5 -1.6)
			(stroke
				(width 0.15)
				(type solid)
			)
			(layer "F.SilkS")
		)
		(fp_line
			(start -0.8 -1.6)
			(end -0.8 -1.3)
			(stroke
				(width 0.15)
				(type solid)
			)
			(layer "F.SilkS")
		)
		(fp_line
			(start -0.85 1.6)
			(end -0.85 1.301)
			(stroke
				(width 0.15)
				(type solid)
			)
			(layer "F.SilkS")
		)
		(fp_circle
			(center -1.25 -1.5)
			(end -1.2 -1.5)
			(stroke
				(width 0.15)
				(type solid)
			)
			(fill yes)
			(layer "F.SilkS")
		)
		(fp_rect
			(start 1.9 -1.76)
			(end -1.9 1.75)
			(stroke
				(width 0.05)
				(type solid)
			)
			(fill no)
			(layer "F.CrtYd")
		)
		(fp_line
			(start -0.398 -1.526)
			(end -0.874 -1.05)
			(stroke
				(width 0.15)
				(type solid)
			)
			(layer "F.Fab")
		)
		(fp_rect
			(start 0.874 1.523)
			(end -0.873 -1.525)
			(stroke
				(width 0.15)
				(type solid)
			)
			(fill no)
			(layer "F.Fab")
		)
		(pad "1" smd rect
			(at -1.351 -0.951 90)
			(size 0.55 1)
			(layers "F.Cu" "F.Mask" "F.Paste")
			(net 314 "VCC")
			(pinfunction "IN")
			(pintype "power_in")
		)
		(pad "2" smd rect
			(at -1.351 0 90)
			(size 0.55 1)
			(layers "F.Cu" "F.Mask" "F.Paste")
			(net 28 "GND")
			(pinfunction "GND")
			(pintype "power_in")
		)
		(pad "3" smd rect
			(at -1.351 0.949 90)
			(size 0.55 1)
			(layers "F.Cu" "F.Mask" "F.Paste")
			(net 314 "VCC")
			(pinfunction "EN")
			(pintype "input")
		)
		(pad "4" smd rect
			(at 1.35 0.949 90)
			(size 0.55 1)
			(layers "F.Cu" "F.Mask" "F.Paste")
			(net 386 "Net-(U6-BYPASS)")
			(pinfunction "BYPASS")
			(pintype "passive")
		)
		(pad "5" smd rect
			(at 1.35 -0.951 90)
			(size 0.55 1)
			(layers "F.Cu" "F.Mask" "F.Paste")
			(net 388 "/Fan controller/+5V")
			(pinfunction "OUT")
			(pintype "power_out")
		)
	)
	(footprint "antmicro-footprints:R_0402_1005Metric"
		(layer "F.Cu")
		(at 70.8 91.305 90)
		(descr "Resistor SMD 0402")
		(tags "resistor SMD 0402")
		(property "Reference" "R102"
			(at 0.785 0.34 90)
			(layer "F.SilkS")
			(effects
				(font
					(size 0.7 0.7)
					(thickness 0.15)
				)
				(justify left bottom)
			)
		)
		(property "Value" "R_22R_0402"
			(at -1.011843 1.772046 90)
			(layer "F.Fab")
			(hide yes)
			(effects
				(font
					(size 0.7 0.7)
					(thickness 0.15)
				)
				(justify left bottom)
			)
		)
		(property "Datasheet" "https://www.bourns.com/docs/product-datasheets/cr.pdf"
			(at 0 0 90)
			(layer "F.Fab")
			(hide yes)
			(effects
				(font
					(size 1.27 1.27)
					(thickness 0.15)
				)
			)
		)
		(property "Description" "SMD Chip Resistor, 22 ohm, ± 1%, 62.5 mW, 0402 [1005 Metric], Thick Film, General Purpose"
			(at 0 0 90)
			(layer "F.Fab")
			(hide yes)
			(effects
				(font
					(size 1.27 1.27)
					(thickness 0.15)
				)
			)
		)
		(property "MPN" "CR0402-FX-22R0GLF"
			(at 0 0 90)
			(unlocked yes)
			(layer "F.Fab")
			(hide yes)
			(effects
				(font
					(size 1 1)
					(thickness 0.15)
				)
			)
		)
		(property "Manufacturer" "Bourns"
			(at 0 0 90)
			(unlocked yes)
			(layer "F.Fab")
			(hide yes)
			(effects
				(font
					(size 1 1)
					(thickness 0.15)
				)
			)
		)
		(property "License" "Apache-2.0"
			(at 0 0 90)
			(unlocked yes)
			(layer "F.Fab")
			(hide yes)
			(effects
				(font
					(size 1 1)
					(thickness 0.15)
				)
			)
		)
		(property "Author" "Antmicro"
			(at 0 0 90)
			(unlocked yes)
			(layer "F.Fab")
			(hide yes)
			(effects
				(font
					(size 1 1)
					(thickness 0.15)
				)
			)
		)
		(property "Val" "22R"
			(at 0 0 90)
			(unlocked yes)
			(layer "F.Fab")
			(hide yes)
			(effects
				(font
					(size 1 1)
					(thickness 0.15)
				)
			)
		)
		(property "Tolerance" "1%"
			(at 0 0 90)
			(unlocked yes)
			(layer "F.Fab")
			(hide yes)
			(effects
				(font
					(size 1 1)
					(thickness 0.15)
				)
			)
		)
		(sheetname "/X710-AT2 Misc/")
		(sheetfile "x710-at2-mics.kicad_sch")
		(attr smd)
		(fp_rect
			(start -0.925 -0.47)
			(end 0.925 0.47)
			(stroke
				(width 0.05)
				(type default)
			)
			(fill no)
			(layer "F.CrtYd")
		)
		(fp_rect
			(start -0.5 -0.25)
			(end 0.5 0.25)
			(stroke
				(width 0.15)
				(type solid)
			)
			(fill no)
			(layer "F.Fab")
		)
		(pad "1" smd roundrect
			(at -0.48 0 90)
			(size 0.59 0.64)
			(layers "F.Cu" "F.Mask" "F.Paste")
			(roundrect_rratio 0.25)
			(net 107 "/X710-AT2 Misc/FLSH_SCK")
			(pintype "passive")
		)
		(pad "2" smd roundrect
			(at 0.48 0 90)
			(size 0.59 0.64)
			(layers "F.Cu" "F.Mask" "F.Paste")
			(roundrect_rratio 0.25)
			(net 106 "/Flash memory/FLASH.CLK")
			(pintype "passive")
		)
	)
	(footprint "antmicro-footprints:C_0603_1608Metric_EIA"
		(layer "F.Cu")
		(at 67.25 115.5 180)
		(descr "Capacitor SMD 0603, IPC-7351 Density Level A")
		(tags "Capacitor 0603")
		(property "Reference" "C170"
			(at 1.22 0.22 0)
			(layer "F.SilkS")
			(effects
				(font
					(size 0.7 0.7)
					(thickness 0.15)
				)
				(justify right top)
			)
		)
		(property "Value" "C_22u_16V_0603"
			(at -1.42757 1.770288 0)
			(layer "F.Fab")
			(hide yes)
			(effects
				(font
					(size 0.7 0.7)
					(thickness 0.15)
				)
				(justify right top)
			)
		)
		(property "Datasheet" "https://product.samsungsem.com/mlcc/CL10A226MO7JZN.do"
			(at 0 0 0)
			(layer "F.Fab")
			(hide yes)
			(effects
				(font
					(size 1.27 1.27)
					(thickness 0.15)
				)
			)
		)
		(property "Description" "SMD Multilayer Ceramic Capacitor"
			(at 0 0 0)
			(layer "F.Fab")
			(hide yes)
			(effects
				(font
					(size 1.27 1.27)
					(thickness 0.15)
				)
			)
		)
		(property "MPN" "CL10A226MO7JZNC"
			(at 0 0 180)
			(unlocked yes)
			(layer "F.Fab")
			(hide yes)
			(effects
				(font
					(size 1 1)
					(thickness 0.15)
				)
			)
		)
		(property "Manufacturer" "Samsung Electro-Mechanics"
			(at 0 0 180)
			(unlocked yes)
			(layer "F.Fab")
			(hide yes)
			(effects
				(font
					(size 1 1)
					(thickness 0.15)
				)
			)
		)
		(property "License" "Apache-2.0"
			(at 0 0 180)
			(unlocked yes)
			(layer "F.Fab")
			(hide yes)
			(effects
				(font
					(size 1 1)
					(thickness 0.15)
				)
			)
		)
		(property "Author" "Antmicro"
			(at 0 0 180)
			(unlocked yes)
			(layer "F.Fab")
			(hide yes)
			(effects
				(font
					(size 1 1)
					(thickness 0.15)
				)
			)
		)
		(property "Val" "22u"
			(at 0 0 180)
			(unlocked yes)
			(layer "F.Fab")
			(hide yes)
			(effects
				(font
					(size 1 1)
					(thickness 0.15)
				)
			)
		)
		(property "Voltage" "16V"
			(at 0 0 180)
			(unlocked yes)
			(layer "F.Fab")
			(hide yes)
			(effects
				(font
					(size 1 1)
					(thickness 0.15)
				)
			)
		)
		(property "Dielectric" ""
			(at 0 0 180)
			(unlocked yes)
			(layer "F.Fab")
			(hide yes)
			(effects
				(font
					(size 1 1)
					(thickness 0.15)
				)
			)
		)
		(sheetname "/X710-AT2 power/")
		(sheetfile "x710-at2-power.kicad_sch")
		(attr smd)
		(fp_line
			(start -0.15 0.55)
			(end 0.15 0.55)
			(stroke
				(width 0.15)
				(type solid)
			)
			(layer "F.SilkS")
		)
		(fp_line
			(start -0.15 -0.55)
			(end 0.15 -0.55)
			(stroke
				(width 0.15)
				(type solid)
			)
			(layer "F.SilkS")
		)
		(fp_rect
			(start -1.25 -0.65)
			(end 1.25 0.65)
			(stroke
				(width 0.05)
				(type solid)
			)
			(fill no)
			(layer "F.CrtYd")
		)
		(fp_rect
			(start -0.8 -0.45)
			(end 0.8 0.45)
			(stroke
				(width 0.15)
				(type solid)
			)
			(fill no)
			(layer "F.Fab")
		)
		(pad "1" smd roundrect
			(at -0.7 0 180)
			(size 0.8 1.1)
			(layers "F.Cu" "F.Mask" "F.Paste")
			(roundrect_rratio 0.2)
			(net 28 "GND")
			(pintype "passive")
		)
		(pad "2" smd roundrect
			(at 0.7 0 180)
			(size 0.8 1.1)
			(layers "F.Cu" "F.Mask" "F.Paste")
			(roundrect_rratio 0.2)
			(net 302 "+1V0")
			(pintype "passive")
		)
	)
)
